(kicad_pcb
	(version 20221018)
	(generator pcbnew)
	(general
    (thickness 1.7403)
  )
	(paper "A4")
	(title_block
    (title "Data Center RDIMM DDR4 Tester")
    (date "2024-09-30")
    (rev "1.2.4")
		(comment 9 "footprints 485-494 of 690")
	)
	(layers
    (0 "F.Cu" signal)
    (1 "In1.Cu" power)
    (2 "In2.Cu" signal)
    (3 "In3.Cu" power)
    (4 "In4.Cu" power)
    (5 "In5.Cu" signal)
    (6 "In6.Cu" power)
    (7 "In7.Cu" signal)
    (8 "In8.Cu" power)
    (9 "In9.Cu" signal)
    (10 "In10.Cu" power)
    (31 "B.Cu" signal)
    (32 "B.Adhes" user "B.Adhesive")
    (33 "F.Adhes" user "F.Adhesive")
    (34 "B.Paste" user)
    (35 "F.Paste" user)
    (36 "B.SilkS" user "B.Silkscreen")
    (37 "F.SilkS" user "F.Silkscreen")
    (38 "B.Mask" user)
    (39 "F.Mask" user)
    (40 "Dwgs.User" user "User.Drawings")
    (41 "Cmts.User" user "User.Comments")
    (42 "Eco1.User" user "User.Eco1")
    (43 "Eco2.User" user "User.Eco2")
    (44 "Edge.Cuts" user)
    (45 "Margin" user)
    (46 "B.CrtYd" user "B.Courtyard")
    (47 "F.CrtYd" user "F.Courtyard")
    (48 "B.Fab" user)
    (49 "F.Fab" user)
  )
	(footprint "data-center-rdimm-ddr4-tester-footprints:C_0402_1005Metric" (layer "B.Cu")
    (at 187.461328 89.785008 180)
    (descr "Capacitor SMD 0402")
    (tags "capacitor SMD 0402")
    (property "Author" "Antmicro")
    (property "Dielectric" "")
    (property "License" "Apache-2.0")
    (property "MPN" "GRM155R61A475MEAAD")
    (property "Manufacturer" "Murata")
    (property "Sheetfile" "fpga-power.kicad_sch")
    (property "Sheetname" "FPGA power")
    (property "Val" "4u7")
    (property "Voltage" "")
    (property "ki_description" " ")
    (attr smd)
    (fp_text reference "C19" (at -19.088672 8.495008) (layer "B.SilkS")
        (effects (font (size 0.7 0.7) (thickness 0.15)) (justify left bottom mirror))
    )
    (fp_text value "C_4u7_0402" (at 0 -1.4) (layer "B.Fab") hide
        (effects (font (size 0.7 0.7) (thickness 0.15)) (justify left bottom mirror))
    )
    (fp_text user "Author: Antmicro" (at -0.932 -4.17) (layer "B.Fab") hide
        (effects (font (size 0.7 0.7) (thickness 0.15)) (justify left bottom mirror))
    )
    (fp_text user "License: Apache-2.0" (at -0.932 -5.17) (layer "B.Fab") hide
        (effects (font (size 0.7 0.7) (thickness 0.15)) (justify left bottom mirror))
    )
    (fp_text user "${REFERENCE}" (at -0.932 -3.168) (layer "B.Fab") hide
        (effects (font (size 0.7 0.7) (thickness 0.15)) (justify left bottom mirror))
    )
    (fp_rect (start -0.94 0.47) (end 0.94 -0.47)
      (stroke (width 0.05) (type solid)) (fill none) (layer "B.CrtYd"))
    (fp_rect (start -0.499 0.249) (end 0.499 -0.249)
      (stroke (width 0.15) (type solid)) (fill none) (layer "B.Fab"))
    (pad "1" smd roundrect (at -0.484 0 180) (size 0.59 0.64) (layers "B.Cu" "B.Paste" "B.Mask") (roundrect_rratio 0.25)
      (net 144 "1V8_SYS") (pintype "passive"))
    (pad "2" smd roundrect (at 0.484 0 180) (size 0.59 0.64) (layers "B.Cu" "B.Paste" "B.Mask") (roundrect_rratio 0.25)
      (net 9 "GND") (pintype "passive"))
  )
	(footprint "data-center-rdimm-ddr4-tester-footprints:C_0201" (layer "B.Cu")
    (at 181.725 77.475)
    (descr "Capacitor SMD 0201")
    (tags "capacitor SMD 0201")
    (property "Author" "Antmicro")
    (property "Dielectric" "")
    (property "License" "Apache-2.0")
    (property "MPN" "CC0201KRX6S5BB104")
    (property "Manufacturer" "Yaego")
    (property "Sheetfile" "fpga-power.kicad_sch")
    (property "Sheetname" "FPGA power")
    (property "Val" "100n")
    (property "Voltage" "")
    (property "ki_description" " ")
    (attr smd)
    (fp_text reference "C74" (at -0.555 0.415 180) (layer "B.SilkS")
        (effects (font (size 0.7 0.7) (thickness 0.15)) (justify left bottom mirror))
    )
    (fp_text value "C_100n_0201" (at 0 -1.4 180) (layer "B.Fab") hide
        (effects (font (size 0.7 0.7) (thickness 0.15)) (justify left bottom mirror))
    )
    (fp_text user "License: Apache-2.0" (at -0.72 -4.4 180) (layer "B.Fab") hide
        (effects (font (size 0.7 0.7) (thickness 0.15)) (justify left bottom mirror))
    )
    (fp_text user "Author: Antmicro" (at -0.72 -5.4 180) (layer "B.Fab") hide
        (effects (font (size 0.7 0.7) (thickness 0.15)) (justify left bottom mirror))
    )
    (fp_text user "${REFERENCE}" (at -0.72 -3.4 180) (layer "B.Fab") hide
        (effects (font (size 0.7 0.7) (thickness 0.15)) (justify left bottom mirror))
    )
    (fp_rect (start -0.72 0.38) (end 0.72 -0.38)
      (stroke (width 0.05) (type solid)) (fill none) (layer "B.CrtYd"))
    (fp_rect (start 0.3 -0.15) (end -0.301 0.149)
      (stroke (width 0.15) (type solid)) (fill none) (layer "B.Fab"))
    (pad "" smd roundrect (at -0.349 0.002) (size 0.318 0.36) (layers "B.Paste") (roundrect_rratio 0.25))
    (pad "" smd roundrect (at 0.341 0.002) (size 0.318 0.36) (layers "B.Paste") (roundrect_rratio 0.25))
    (pad "1" smd roundrect (at -0.321 0.002) (size 0.46 0.4) (layers "B.Cu" "B.Mask") (roundrect_rratio 0.25)
      (net 77 "VDDQ") (pintype "passive"))
    (pad "2" smd roundrect (at 0.32 0.002) (size 0.46 0.4) (layers "B.Cu" "B.Mask") (roundrect_rratio 0.25)
      (net 9 "GND") (pintype "passive"))
  )
	(footprint "data-center-rdimm-ddr4-tester-footprints:C_0201" (layer "B.Cu")
    (at 190.076328 91.820008 90)
    (descr "Capacitor SMD 0201")
    (tags "capacitor SMD 0201")
    (property "Author" "Antmicro")
    (property "Dielectric" "")
    (property "License" "Apache-2.0")
    (property "MPN" "CC0201KRX6S5BB104")
    (property "Manufacturer" "Yaego")
    (property "Sheetfile" "fpga-power.kicad_sch")
    (property "Sheetname" "FPGA power")
    (property "Val" "100n")
    (property "Voltage" "")
    (property "ki_description" " ")
    (attr smd)
    (fp_text reference "C52" (at 2.740008 0.393672 270) (layer "B.SilkS")
        (effects (font (size 0.7 0.7) (thickness 0.15)) (justify left bottom mirror))
    )
    (fp_text value "C_100n_0201" (at 0 -1.4 270) (layer "B.Fab") hide
        (effects (font (size 0.7 0.7) (thickness 0.15)) (justify left bottom mirror))
    )
    (fp_text user "${REFERENCE}" (at -0.72 -3.4 270) (layer "B.Fab") hide
        (effects (font (size 0.7 0.7) (thickness 0.15)) (justify left bottom mirror))
    )
    (fp_text user "License: Apache-2.0" (at -0.72 -4.4 270) (layer "B.Fab") hide
        (effects (font (size 0.7 0.7) (thickness 0.15)) (justify left bottom mirror))
    )
    (fp_text user "Author: Antmicro" (at -0.72 -5.4 270) (layer "B.Fab") hide
        (effects (font (size 0.7 0.7) (thickness 0.15)) (justify left bottom mirror))
    )
    (fp_rect (start -0.72 0.38) (end 0.72 -0.38)
      (stroke (width 0.05) (type solid)) (fill none) (layer "B.CrtYd"))
    (fp_rect (start 0.3 -0.15) (end -0.301 0.149)
      (stroke (width 0.15) (type solid)) (fill none) (layer "B.Fab"))
    (pad "" smd roundrect (at -0.349 0.002 90) (size 0.318 0.36) (layers "B.Paste") (roundrect_rratio 0.25))
    (pad "" smd roundrect (at 0.341 0.002 90) (size 0.318 0.36) (layers "B.Paste") (roundrect_rratio 0.25))
    (pad "1" smd roundrect (at -0.321 0.002 90) (size 0.46 0.4) (layers "B.Cu" "B.Mask") (roundrect_rratio 0.25)
      (net 147 "1V0_SYS") (pintype "passive"))
    (pad "2" smd roundrect (at 0.32 0.002 90) (size 0.46 0.4) (layers "B.Cu" "B.Mask") (roundrect_rratio 0.25)
      (net 9 "GND") (pintype "passive"))
  )
	(footprint "data-center-rdimm-ddr4-tester-footprints:C_0402_1005Metric" (layer "B.Cu")
    (at 185.425 78.275 180)
    (descr "Capacitor SMD 0402")
    (tags "capacitor SMD 0402")
    (property "Author" "Antmicro")
    (property "Dielectric" "X5R")
    (property "License" "Apache-2.0")
    (property "MPN" "GRM155R61H104KE14D")
    (property "Manufacturer" "Murata")
    (property "Sheetfile" "fpga-banks-16-34.kicad_sch")
    (property "Sheetname" "FPGA banks 16-34")
    (property "Val" "100n")
    (property "Voltage" "50V")
    (property "ki_description" " ")
    (attr smd)
    (fp_text reference "C18" (at 0.705 0.125) (layer "B.SilkS")
        (effects (font (size 0.7 0.7) (thickness 0.15)) (justify left bottom mirror))
    )
    (fp_text value "C_100n_0402" (at 0 -1.4) (layer "B.Fab") hide
        (effects (font (size 0.7 0.7) (thickness 0.15)) (justify left bottom mirror))
    )
    (fp_text user "${REFERENCE}" (at -0.932 -3.168) (layer "B.Fab") hide
        (effects (font (size 0.7 0.7) (thickness 0.15)) (justify left bottom mirror))
    )
    (fp_text user "License: Apache-2.0" (at -0.932 -5.17) (layer "B.Fab") hide
        (effects (font (size 0.7 0.7) (thickness 0.15)) (justify left bottom mirror))
    )
    (fp_text user "Author: Antmicro" (at -0.932 -4.17) (layer "B.Fab") hide
        (effects (font (size 0.7 0.7) (thickness 0.15)) (justify left bottom mirror))
    )
    (fp_rect (start -0.94 0.47) (end 0.94 -0.47)
      (stroke (width 0.05) (type solid)) (fill none) (layer "B.CrtYd"))
    (fp_rect (start -0.499 0.249) (end 0.499 -0.249)
      (stroke (width 0.15) (type solid)) (fill none) (layer "B.Fab"))
    (pad "1" smd roundrect (at -0.484 0 180) (size 0.59 0.64) (layers "B.Cu" "B.Paste" "B.Mask") (roundrect_rratio 0.25)
      (net 312 "VREF_33") (pintype "passive"))
    (pad "2" smd roundrect (at 0.484 0 180) (size 0.59 0.64) (layers "B.Cu" "B.Paste" "B.Mask") (roundrect_rratio 0.25)
      (net 9 "GND") (pintype "passive"))
  )
	(footprint "data-center-rdimm-ddr4-tester-footprints:C_0402_1005Metric" (layer "B.Cu")
    (at 185.425 77.25 180)
    (descr "Capacitor SMD 0402")
    (tags "capacitor SMD 0402")
    (property "Author" "Antmicro")
    (property "Dielectric" "X5R")
    (property "License" "Apache-2.0")
    (property "MPN" "GRM155R61H104KE14D")
    (property "Manufacturer" "Murata")
    (property "Sheetfile" "fpga-banks-16-34.kicad_sch")
    (property "Sheetname" "FPGA banks 16-34")
    (property "Val" "100n")
    (property "Voltage" "50V")
    (property "ki_description" " ")
    (attr smd)
    (fp_text reference "C146" (at 0.655 0.13) (layer "B.SilkS")
        (effects (font (size 0.7 0.7) (thickness 0.15)) (justify left bottom mirror))
    )
    (fp_text value "C_100n_0402" (at 0 -1.4) (layer "B.Fab") hide
        (effects (font (size 0.7 0.7) (thickness 0.15)) (justify left bottom mirror))
    )
    (fp_text user "License: Apache-2.0" (at -0.932 -5.17) (layer "B.Fab") hide
        (effects (font (size 0.7 0.7) (thickness 0.15)) (justify left bottom mirror))
    )
    (fp_text user "${REFERENCE}" (at -0.932 -3.168) (layer "B.Fab") hide
        (effects (font (size 0.7 0.7) (thickness 0.15)) (justify left bottom mirror))
    )
    (fp_text user "Author: Antmicro" (at -0.932 -4.17) (layer "B.Fab") hide
        (effects (font (size 0.7 0.7) (thickness 0.15)) (justify left bottom mirror))
    )
    (fp_rect (start -0.94 0.47) (end 0.94 -0.47)
      (stroke (width 0.05) (type solid)) (fill none) (layer "B.CrtYd"))
    (fp_rect (start -0.499 0.249) (end 0.499 -0.249)
      (stroke (width 0.15) (type solid)) (fill none) (layer "B.Fab"))
    (pad "1" smd roundrect (at -0.484 0 180) (size 0.59 0.64) (layers "B.Cu" "B.Paste" "B.Mask") (roundrect_rratio 0.25)
      (net 312 "VREF_33") (pintype "passive"))
    (pad "2" smd roundrect (at 0.484 0 180) (size 0.59 0.64) (layers "B.Cu" "B.Paste" "B.Mask") (roundrect_rratio 0.25)
      (net 9 "GND") (pintype "passive"))
  )
	(footprint "data-center-rdimm-ddr4-tester-footprints:R_0603_1608Metric" (layer "B.Cu")
    (at 187.75 77.275 90)
    (descr "Resistor SMD 0603")
    (tags "resistor SMD 0603")
    (property "Author" "Antmicro")
    (property "License" "Apache-2.0")
    (property "MPN" "CR0603-FX-1001ELF")
    (property "Manufacturer" "Bourns")
    (property "Sheetfile" "fpga-banks-16-34.kicad_sch")
    (property "Sheetname" "FPGA banks 16-34")
    (property "Tolerance" "1%")
    (property "Val" "1k")
    (property "ki_description" "1k resistor in 0603 package with 1% tolerance")
    (attr smd)
    (fp_text reference "R65" (at 3.235 0.4 270) (layer "B.SilkS")
        (effects (font (size 0.7 0.7) (thickness 0.15)) (justify left bottom mirror))
    )
    (fp_text value "R_1k_0603" (at 0 -1.6 270) (layer "B.Fab") hide
        (effects (font (size 0.7 0.7) (thickness 0.15)) (justify left bottom mirror))
    )
    (fp_text user "License: Apache-2.0" (at -1.25 -5.9 270) (layer "B.Fab") hide
        (effects (font (size 0.7 0.7) (thickness 0.15)) (justify left bottom mirror))
    )
    (fp_text user "Author: Antmicro" (at -1.25 -4.9 270) (layer "B.Fab") hide
        (effects (font (size 0.7 0.7) (thickness 0.15)) (justify left bottom mirror))
    )
    (fp_text user "${REFERENCE}" (at -1.25 -3.898 270) (layer "B.Fab") hide
        (effects (font (size 0.7 0.7) (thickness 0.15)) (justify left bottom mirror))
    )
    (fp_line (start -0.3 -0.3) (end 0.3 -0.3)
      (stroke (width 0.15) (type solid)) (layer "B.SilkS"))
    (fp_line (start -0.3 0.3) (end 0.3 0.3)
      (stroke (width 0.15) (type solid)) (layer "B.SilkS"))
    (fp_rect (start -1.25 0.7) (end 1.25 -0.7)
      (stroke (width 0.05) (type solid)) (fill none) (layer "B.CrtYd"))
    (fp_rect (start -0.8 0.4) (end 0.8 -0.4)
      (stroke (width 0.15) (type solid)) (fill none) (layer "B.Fab"))
    (pad "1" smd roundrect (at -0.7 0 90) (size 0.6 0.8) (layers "B.Cu" "B.Paste" "B.Mask") (roundrect_rratio 0.2)
      (net 77 "VDDQ") (pintype "passive"))
    (pad "2" smd roundrect (at 0.7 0 90) (size 0.6 0.8) (layers "B.Cu" "B.Paste" "B.Mask") (roundrect_rratio 0.2)
      (net 312 "VREF_33") (pintype "passive"))
  )
	(footprint "data-center-rdimm-ddr4-tester-footprints:Testpoint_smd_1mm" (layer "B.Cu")
    (at 148.176328 107.619208)
    (property "Author" "Antmicro")
    (property "License" "Apache-2.0")
    (property "MPN" "")
    (property "Manufacturer" "")
    (property "Sheetfile" "interfaces.kicad_sch")
    (property "Sheetname" "Interfaces")
    (property "ki_description" "Test Point 1mm")
    (attr exclude_from_pos_files)
    (fp_text reference "TP11" (at 0 0.731898 180) (layer "B.SilkS")
        (effects (font (size 0.7 0.7) (thickness 0.15)) (justify left bottom mirror))
    )
    (fp_text value "TP_1mm_SMD" (at 0 -1.4 180) (layer "B.Fab") hide
        (effects (font (size 0.7 0.7) (thickness 0.15)) (justify left bottom mirror))
    )
    (fp_text user "${REFERENCE}" (at -0.5 -2.8 180) (layer "B.Fab") hide
        (effects (font (size 0.7 0.7) (thickness 0.15)) (justify left bottom mirror))
    )
    (fp_text user "License: Apache-2.0" (at -0.5 -5.2 180) (layer "B.Fab") hide
        (effects (font (size 0.7 0.7) (thickness 0.15)) (justify left bottom mirror))
    )
    (fp_text user "Author: Antmicro" (at -0.5 -4 180) (layer "B.Fab") hide
        (effects (font (size 0.7 0.7) (thickness 0.15)) (justify left bottom mirror))
    )
    (pad "1" smd circle (at 0 0) (size 1 1) (layers "B.Cu" "B.Mask")
      (net 665 "Net-(U7-ADBUS5)") (pinfunction "1") (pintype "passive"))
  )
	(footprint "data-center-rdimm-ddr4-tester-footprints:Testpoint_smd_1mm" (layer "B.Cu")
    (at 170.666328 105.200008 -90)
    (property "Author" "Antmicro")
    (property "License" "Apache-2.0")
    (property "MPN" "")
    (property "Manufacturer" "")
    (property "Sheetfile" "config-spi.kicad_sch")
    (property "Sheetname" "Config SPI flash")
    (property "ki_description" "Test Point 1mm")
    (attr exclude_from_pos_files)
    (fp_text reference "EMCCLK1" (at 1.469992 -2.423672 180) (layer "B.SilkS")
        (effects (font (size 0.7 0.7) (thickness 0.15)) (justify left bottom mirror))
    )
    (fp_text value "TP_1mm_SMD" (at 0 -1.4 90) (layer "B.Fab") hide
        (effects (font (size 0.7 0.7) (thickness 0.15)) (justify left bottom mirror))
    )
    (fp_text user "License: Apache-2.0" (at -0.5 -5.2 90) (layer "B.Fab") hide
        (effects (font (size 0.7 0.7) (thickness 0.15)) (justify left bottom mirror))
    )
    (fp_text user "Author: Antmicro" (at -0.5 -4 90) (layer "B.Fab") hide
        (effects (font (size 0.7 0.7) (thickness 0.15)) (justify left bottom mirror))
    )
    (fp_text user "${REFERENCE}" (at -0.5 -2.8 90) (layer "B.Fab") hide
        (effects (font (size 0.7 0.7) (thickness 0.15)) (justify left bottom mirror))
    )
    (pad "1" smd circle (at 0 0 270) (size 1 1) (layers "B.Cu" "B.Mask")
      (net 99 "EMCCLK") (pinfunction "1") (pintype "passive"))
  )
	(footprint "data-center-rdimm-ddr4-tester-footprints:R_0603_1608Metric" (layer "B.Cu")
    (at 185.725 75.975 180)
    (descr "Resistor SMD 0603")
    (tags "resistor SMD 0603")
    (property "Author" "Antmicro")
    (property "License" "Apache-2.0")
    (property "MPN" "CR0603-FX-1001ELF")
    (property "Manufacturer" "Bourns")
    (property "Sheetfile" "fpga-banks-16-34.kicad_sch")
    (property "Sheetname" "FPGA banks 16-34")
    (property "Tolerance" "1%")
    (property "Val" "1k")
    (property "ki_description" "1k resistor in 0603 package with 1% tolerance")
    (attr smd)
    (fp_text reference "R66" (at 1.035 -0.185) (layer "B.SilkS")
        (effects (font (size 0.7 0.7) (thickness 0.15)) (justify left bottom mirror))
    )
    (fp_text value "R_1k_0603" (at 0 -1.6) (layer "B.Fab") hide
        (effects (font (size 0.7 0.7) (thickness 0.15)) (justify left bottom mirror))
    )
    (fp_text user "${REFERENCE}" (at -1.25 -3.898) (layer "B.Fab") hide
        (effects (font (size 0.7 0.7) (thickness 0.15)) (justify left bottom mirror))
    )
    (fp_text user "Author: Antmicro" (at -1.25 -4.9) (layer "B.Fab") hide
        (effects (font (size 0.7 0.7) (thickness 0.15)) (justify left bottom mirror))
    )
    (fp_text user "License: Apache-2.0" (at -1.25 -5.9) (layer "B.Fab") hide
        (effects (font (size 0.7 0.7) (thickness 0.15)) (justify left bottom mirror))
    )
    (fp_line (start -0.3 -0.3) (end 0.3 -0.3)
      (stroke (width 0.15) (type solid)) (layer "B.SilkS"))
    (fp_line (start -0.3 0.3) (end 0.3 0.3)
      (stroke (width 0.15) (type solid)) (layer "B.SilkS"))
    (fp_rect (start -1.25 0.7) (end 1.25 -0.7)
      (stroke (width 0.05) (type solid)) (fill none) (layer "B.CrtYd"))
    (fp_rect (start -0.8 0.4) (end 0.8 -0.4)
      (stroke (width 0.15) (type solid)) (fill none) (layer "B.Fab"))
    (pad "1" smd roundrect (at -0.7 0 180) (size 0.6 0.8) (layers "B.Cu" "B.Paste" "B.Mask") (roundrect_rratio 0.2)
      (net 312 "VREF_33") (pintype "passive"))
    (pad "2" smd roundrect (at 0.7 0 180) (size 0.6 0.8) (layers "B.Cu" "B.Paste" "B.Mask") (roundrect_rratio 0.2)
      (net 9 "GND") (pintype "passive"))
  )
	(footprint "data-center-rdimm-ddr4-tester-footprints:R_0402_1005Metric" (layer "B.Cu")
    (at 158.686328 89.010008 -90)
    (descr "Resistor SMD 0402")
    (tags "resistor SMD 0402")
    (property "Author" "Antmicro")
    (property "License" "Apache-2.0")
    (property "MPN" "CR0402-FX-2201GLF")
    (property "Manufacturer" "Bourns")
    (property "Sheetfile" "ethernet.kicad_sch")
    (property "Sheetname" "Ethernet")
    (property "Tolerance" "1%")
    (property "Val" "2k2")
    (property "ki_description" "2k2 resistor in 0402 package with 1% tolerance")
    (attr smd)
    (fp_text reference "R89" (at -1.165008 -7.958672 90) (layer "B.SilkS")
        (effects (font (size 0.7 0.7) (thickness 0.15)) (justify left bottom mirror))
    )
    (fp_text value "R_2k2_0402" (at 0 -1.4 90) (layer "B.Fab") hide
        (effects (font (size 0.7 0.7) (thickness 0.15)) (justify left bottom mirror))
    )
    (fp_text user "Author: Antmicro" (at -0.95 -4.169 90) (layer "B.Fab") hide
        (effects (font (size 0.7 0.7) (thickness 0.15)) (justify left bottom mirror))
    )
    (fp_text user "${REFERENCE}" (at -0.95 -3.168 90) (layer "B.Fab") hide
        (effects (font (size 0.7 0.7) (thickness 0.15)) (justify left bottom mirror))
    )
    (fp_text user "License: Apache-2.0" (at -0.95 -5.169 90) (layer "B.Fab") hide
        (effects (font (size 0.7 0.7) (thickness 0.15)) (justify left bottom mirror))
    )
    (fp_rect (start -0.93 0.47) (end 0.93 -0.47)
      (stroke (width 0.05) (type solid)) (fill none) (layer "B.CrtYd"))
    (fp_rect (start -0.5 0.25) (end 0.5 -0.25)
      (stroke (width 0.15) (type solid)) (fill none) (layer "B.Fab"))
    (pad "1" smd roundrect (at -0.485 0 270) (size 0.59 0.64) (layers "B.Cu" "B.Paste" "B.Mask") (roundrect_rratio 0.25)
      (net 27 "ETH_RXD1") (pintype "passive"))
    (pad "2" smd roundrect (at 0.485 0 270) (size 0.59 0.64) (layers "B.Cu" "B.Paste" "B.Mask") (roundrect_rratio 0.25)
      (net 9 "GND") (pintype "passive"))
  )
)
